# T6G (Grand Teton) — schematic netlist excerpt (pin names and nets, part order shuffled) for the footprints in the layout excerpt that follows; sources: Cadence DE-HDL packaged netlist, KiCad conversion of 04192023_DAF0TMB3IC0_F0TG_MB_C_brd_V02_OCP.brd

C2221  Q_CAP  22UF 4V 20% X6S  pkg C0402  page 69 : A = PVDDCR_CPU1_P0 ; B = GND
C3915  Q_CAP  22UF 4V 20% X6S  pkg C0402  page 74 : A = PVDDCR_SOC_P1 ; B = GND

(kicad_pcb
	(version 20260206)
	(generator "pcbnew")
	(generator_version "10.0")
	(general
		(thickness 1.6)
		(legacy_teardrops no)
	)
	(paper "A4")
	(title_block
		(title "04192023_DAF0TMB3IC0_F0TG_MB_C_brd_V02_OCP.brd")
		(comment 1 "Grand Teton / footprints 7971-7972 of 8354")
	)
	(layers
		(0 "F.Cu" signal "TOP")
		(4 "In1.Cu" signal "GND")
		(6 "In2.Cu" signal "IN1")
		(8 "In3.Cu" signal "GND1")
		(10 "In4.Cu" signal "IN2")
		(12 "In5.Cu" signal "GND2")
		(14 "In6.Cu" signal "IN3")
		(16 "In7.Cu" signal "GND3")
		(18 "In8.Cu" signal "VCC")
		(20 "In9.Cu" signal "VCC1")
		(22 "In10.Cu" signal "GND4")
		(24 "In11.Cu" signal "IN4")
		(26 "In12.Cu" signal "GND5")
		(28 "In13.Cu" signal "IN5")
		(30 "In14.Cu" signal "GND6")
		(32 "In15.Cu" signal "IN6")
		(34 "In16.Cu" signal "GND7")
		(2 "B.Cu" signal "BOTTOM")
		(9 "F.Adhes" user "F.Adhesive")
		(11 "B.Adhes" user "B.Adhesive")
		(13 "F.Paste" user "Package Geometry/Pastemask Top")
		(15 "B.Paste" user "Package Geometry/Pastemask Bottom")
		(5 "F.SilkS" user "Ref Des/Silkscreen Top")
		(7 "B.SilkS" user "Ref Des/Silkscreen Bottom")
		(1 "F.Mask" user "Board Geometry/Soldermask Top")
		(3 "B.Mask" user "Board Geometry/Soldermask Bottom")
		(17 "Dwgs.User" user "User.Drawings")
		(19 "Cmts.User" user "User.Comments")
		(21 "Eco1.User" user "User.Eco1")
		(23 "Eco2.User" user "User.Eco2")
		(25 "Edge.Cuts" user "Board Geometry/Outline")
		(27 "Margin" user)
		(31 "F.CrtYd" user "Package Geometry/Place Bound Top")
		(29 "B.CrtYd" user "Package Geometry/Place Bound Bottom")
		(35 "F.Fab" user "Ref Des/Assembly Top")
		(33 "B.Fab" user "Ref Des/Assembly Bottom")
	)
	(footprint ""
		(layer "B.Cu")
		(at 364.788958 -272.284952)
		(property "Reference" "C2221"
			(at 0 0 0)
			(layer "B.SilkS")
			(hide yes)
			(effects
				(font
					(size 1.27 1.27)
				)
				(justify mirror)
			)
		)
		(property "Value" ""
			(at 0 0 0)
			(layer "B.Fab")
			(effects
				(font
					(size 1.27 1.27)
				)
				(justify mirror)
			)
		)
		(duplicate_pad_numbers_are_jumpers no)
		(fp_line
			(start -0.7874 -0.4064)
			(end -0.7874 0.4064)
			(stroke
				(width 0.1524)
				(type default)
			)
			(layer "B.SilkS")
		)
		(fp_line
			(start -0.7874 0.4064)
			(end 0.7874 0.4064)
			(stroke
				(width 0.1524)
				(type default)
			)
			(layer "B.SilkS")
		)
		(fp_line
			(start 0.7874 -0.4064)
			(end -0.7874 -0.4064)
			(stroke
				(width 0.1524)
				(type default)
			)
			(layer "B.SilkS")
		)
		(fp_line
			(start 0.7874 0.4064)
			(end 0.7874 -0.4064)
			(stroke
				(width 0.1524)
				(type default)
			)
			(layer "B.SilkS")
		)
		(fp_line
			(start -0.67945 -0.3048)
			(end -0.67945 0.3048)
			(stroke
				(width 0.1)
				(type default)
			)
			(layer "B.Fab")
		)
		(fp_line
			(start -0.67945 0.3048)
			(end -0.120396 0.3048)
			(stroke
				(width 0.1)
				(type default)
			)
			(layer "B.Fab")
		)
		(fp_line
			(start -0.12065 -0.3048)
			(end -0.67945 -0.3048)
			(stroke
				(width 0.1)
				(type default)
			)
			(layer "B.Fab")
		)
		(fp_line
			(start -0.12065 -0.2794)
			(end -0.12065 -0.3048)
			(stroke
				(width 0.1)
				(type default)
			)
			(layer "B.Fab")
		)
		(fp_line
			(start -0.120396 0.2794)
			(end 0.12065 0.2794)
			(stroke
				(width 0.1)
				(type default)
			)
			(layer "B.Fab")
		)
		(fp_line
			(start -0.120396 0.3048)
			(end -0.120396 0.2794)
			(stroke
				(width 0.1)
				(type default)
			)
			(layer "B.Fab")
		)
		(fp_line
			(start 0.12065 -0.305054)
			(end 0.12065 -0.2794)
			(stroke
				(width 0.1)
				(type default)
			)
			(layer "B.Fab")
		)
		(fp_line
			(start 0.12065 -0.2794)
			(end -0.12065 -0.2794)
			(stroke
				(width 0.1)
				(type default)
			)
			(layer "B.Fab")
		)
		(fp_line
			(start 0.12065 0.2794)
			(end 0.12065 0.3048)
			(stroke
				(width 0.1)
				(type default)
			)
			(layer "B.Fab")
		)
		(fp_line
			(start 0.12065 0.3048)
			(end 0.67945 0.3048)
			(stroke
				(width 0.1)
				(type default)
			)
			(layer "B.Fab")
		)
		(fp_line
			(start 0.67945 -0.305054)
			(end 0.12065 -0.305054)
			(stroke
				(width 0.1)
				(type default)
			)
			(layer "B.Fab")
		)
		(fp_line
			(start 0.67945 0.3048)
			(end 0.67945 -0.305054)
			(stroke
				(width 0.1)
				(type default)
			)
			(layer "B.Fab")
		)
		(pad "1" smd circle
			(at 0.40005 0 180)
			(size 0 0)
			(layers "B.Cu" "B.Mask" "B.Paste")
			(net "PVDDCR_CPU1_P0")
		)
		(pad "2" smd circle
			(at -0.40005 0 180)
			(size 0 0)
			(layers "B.Cu" "B.Mask" "B.Paste")
			(net "GND")
		)
	)
	(footprint ""
		(layer "B.Cu")
		(at 123.611386 -257.930396)
		(property "Reference" "C3915"
			(at 0 0 0)
			(layer "B.SilkS")
			(hide yes)
			(effects
				(font
					(size 1.27 1.27)
				)
				(justify mirror)
			)
		)
		(property "Value" ""
			(at 0 0 0)
			(layer "B.Fab")
			(effects
				(font
					(size 1.27 1.27)
				)
				(justify mirror)
			)
		)
		(duplicate_pad_numbers_are_jumpers no)
		(fp_line
			(start -0.7874 -0.4064)
			(end -0.7874 0.4064)
			(stroke
				(width 0.1524)
				(type default)
			)
			(layer "B.SilkS")
		)
		(fp_line
			(start -0.7874 0.4064)
			(end 0.7874 0.4064)
			(stroke
				(width 0.1524)
				(type default)
			)
			(layer "B.SilkS")
		)
		(fp_line
			(start 0.7874 -0.4064)
			(end -0.7874 -0.4064)
			(stroke
				(width 0.1524)
				(type default)
			)
			(layer "B.SilkS")
		)
		(fp_line
			(start 0.7874 0.4064)
			(end 0.7874 -0.4064)
			(stroke
				(width 0.1524)
				(type default)
			)
			(layer "B.SilkS")
		)
		(fp_line
			(start -0.67945 -0.3048)
			(end -0.67945 0.3048)
			(stroke
				(width 0.1)
				(type default)
			)
			(layer "B.Fab")
		)
		(fp_line
			(start -0.67945 0.3048)
			(end -0.120396 0.3048)
			(stroke
				(width 0.1)
				(type default)
			)
			(layer "B.Fab")
		)
		(fp_line
			(start -0.12065 -0.3048)
			(end -0.67945 -0.3048)
			(stroke
				(width 0.1)
				(type default)
			)
			(layer "B.Fab")
		)
		(fp_line
			(start -0.12065 -0.2794)
			(end -0.12065 -0.3048)
			(stroke
				(width 0.1)
				(type default)
			)
			(layer "B.Fab")
		)
		(fp_line
			(start -0.120396 0.2794)
			(end 0.12065 0.2794)
			(stroke
				(width 0.1)
				(type default)
			)
			(layer "B.Fab")
		)
		(fp_line
			(start -0.120396 0.3048)
			(end -0.120396 0.2794)
			(stroke
				(width 0.1)
				(type default)
			)
			(layer "B.Fab")
		)
		(fp_line
			(start 0.12065 -0.305054)
			(end 0.12065 -0.2794)
			(stroke
				(width 0.1)
				(type default)
			)
			(layer "B.Fab")
		)
		(fp_line
			(start 0.12065 -0.2794)
			(end -0.12065 -0.2794)
			(stroke
				(width 0.1)
				(type default)
			)
			(layer "B.Fab")
		)
		(fp_line
			(start 0.12065 0.2794)
			(end 0.12065 0.3048)
			(stroke
				(width 0.1)
				(type default)
			)
			(layer "B.Fab")
		)
		(fp_line
			(start 0.12065 0.3048)
			(end 0.67945 0.3048)
			(stroke
				(width 0.1)
				(type default)
			)
			(layer "B.Fab")
		)
		(fp_line
			(start 0.67945 -0.305054)
			(end 0.12065 -0.305054)
			(stroke
				(width 0.1)
				(type default)
			)
			(layer "B.Fab")
		)
		(fp_line
			(start 0.67945 0.3048)
			(end 0.67945 -0.305054)
			(stroke
				(width 0.1)
				(type default)
			)
			(layer "B.Fab")
		)
		(pad "1" smd circle
			(at 0.40005 0 180)
			(size 0 0)
			(layers "B.Cu" "B.Mask" "B.Paste")
			(net "PVDDCR_SOC_P1")
		)
		(pad "2" smd circle
			(at -0.40005 0 180)
			(size 0 0)
			(layers "B.Cu" "B.Mask" "B.Paste")
			(net "GND")
		)
	)
)
